FILE_TYPE = CONNECTIVITY;
{Allegro Design Entry HDL 17.4-2019 S026 (4007227) 1/17/2022}
"PAGE_NUMBER" = 333;
0"NC";
1"GND\g";
2"P3V3_AUX\g";
3"GND\g";
4"GND\g";
5"GND\g";
6"GND\g";
7"P3V3_AUX\g";
8"GND\g";
9"GND\g";
10"GND\g";
11"GND\g";
12"P3V3_AUX\g";
13"GND\g";
14"P3V3_AUX\g";
15"P3V3_AUX\g";
16"GND\g";
17"GND\g";
18"P3V3_AUX\g";
19"GND\g";
20"GND\g";
21"P3V3_AUX\g";
22"GND\g";
23"GND\g";
24"P3V3_AUX\g";
25"GND\g";
26"P3V3_AUX\g";
27"P3V3_AUX\g";
28"GND\g";
29"P3V3_AUX\g";
30"GND\g";
31"P3V3_AUX\g";
32"GND\g";
33"P3V3_AUX\g";
34"GND\g";
35"P3V3_AUX\g";
36"GND\g";
37"P3V3_AUX\g";
38"GND\g";
39"P3V3_AUX\g";
40"P3V3_AUX\g";
41"P3V3_AUX\g";
42"P3V3_AUX\g";
43"P3V3_AUX\g";
44"P3V3_AUX\g";
45"GND\g";
46"GND\g";
47"GND\g";
48"GND\g";
49"GND\g";
50"GND\g";
51"P3V3_AUX\g";
52"GND\g";
53"P3V3_AUX\g";
54"GND\g";
55"GND\g";
56"P3V3_AUX\g";
57"FM_GPU_PWRGD";
58"FM_SWB_PWRGD";
59"FM_SWB_BIC_READY_ISO_N";
60"RST_BMC_FROM_SWB_ISO_N";
61"GPU_FPGA_READY_ISO";
62"FM_SWB_PWRGD_ISO";
63"FM_SMB_2_ALERT_GPU_ISO_N";
64"BIC_MONITER_ISO";
65"FM_SMB_1_ALERT_GPU_ISO_N";
66"FM_GPU_PWRGD_ISO";
67"FM_SWB_BIC_READY_N";
68"FM_SWB_BIC_READY";
69"FM_SMB_2_ALERT_GPU_N";
70"RST_BMC_FROM_SWB_N";
71"BIC_MONITER";
72"RST_BMC_FROM_SWB";
73"FM_SWB_PWRGD_N";
74"FM_GPU_PWRGD_N";
75"FM_SMB_1_ALERT_GPU";
76"FM_SMB_1_ALERT_GPU_N";
77"GPU_FPGA_READY_N";
78"GPU_FPGA_READY";
79"BIC_MONITER_N";
80"FM_SMB_2_ALERT_GPU";
%"UNIVERSAL_GND"
"1","(-3525,7025)","0","pure_quanta_power","I10";
;
CDS_LIB"pure_quanta_power"
HDL_POWER"GND";
"A"1;
%"MOSFET_NCH_DUAL"
"2","(1875,7800)","0","pure_quanta","I100";
;
LOCATION"Q71"
$SEC"2"
CDS_SEC"2"
MATERIAL"IC"
VALUE"PJT138K"
PART_TYPE"SMLF"
CDS_LMAN_SYM_OUTLINE"-150,150,150,-150"
NEEDS_NO_SIZE"TRUE"
CDS_LIB"pure_quanta"
PART_NUMBER"BAM138K0003";
"S2"
$PN"4"3;
"G2"
$PN"5"73;
"D2"
$PN"3"62;
%"Q_RES"
"2","(1925,8175)","0","pure_quanta","I101";
;
LOCATION"R2934"
$SEC"1"
CDS_SEC"1"
PACK_TYPE"0402LF"
WATTAGE"1/16W"
MATERIAL"CHIP"
VALUE"100K"
TOLERANCE"1%"
CDS_LIB"pure_quanta"
PART_NUMBER"CS41002FB09";
"A"
$PN"1"2;
"B"
$PN"2"62;
%"UNIVERSAL_POWER"
"1","(1925,8475)","0","pure_quanta_power","I102";
;
HDL_POWER"P3V3_AUX"
CDS_LIB"pure_quanta_power";
"A"2;
%"UNIVERSAL_GND"
"1","(1925,7425)","0","pure_quanta_power","I103";
;
CDS_LIB"pure_quanta_power"
HDL_POWER"GND";
"A"3;
%"UNIVERSAL_GND"
"1","(2925,6050)","0","pure_quanta_power","I104";
;
CDS_LIB"pure_quanta_power"
HDL_POWER"GND";
"A"4;
%"Q_CAP"
"1","(2925,6250)","0","pure_quanta","I105";
;
LOCATION"C1756"
$SEC"1"
CDS_SEC"1"
VALUE"0.1UF"
VOLTAGE"25V"
TOLERANCE"10%"
MATERIAL"X7R"
PACK_TYPE"0402"
CDS_LIB"pure_quanta"
PART_NUMBER"CH4104K1B00";
"B"
$PN"2"4;
"A"
$PN"1"66;
%"UNIVERSAL_GND"
"1","(2025,6050)","0","pure_quanta_power","I108";
;
CDS_LIB"pure_quanta_power"
HDL_POWER"GND";
"A"5;
%"Q_RES"
"2","(2025,6875)","0","pure_quanta","I109";
;
LOCATION"R2935"
$SEC"1"
CDS_SEC"1"
PACK_TYPE"0402LF"
WATTAGE"1/16W"
MATERIAL"CHIP"
VALUE"100K"
TOLERANCE"1%"
CDS_LIB"pure_quanta"
PART_NUMBER"CS41002FB09";
"A"
$PN"1"7;
"B"
$PN"2"66;
%"UNIVERSAL_GND"
"1","(-3475,5625)","0","pure_quanta_power","I11";
;
CDS_LIB"pure_quanta_power"
HDL_POWER"GND";
"A"6;
%"UNIVERSAL_POWER"
"1","(2025,7175)","0","pure_quanta_power","I110";
;
HDL_POWER"P3V3_AUX"
CDS_LIB"pure_quanta_power";
"A"7;
%"Q_CAP"
"1","(2875,7775)","0","pure_quanta","I111";
;
LOCATION"C1774"
$SEC"1"
CDS_SEC"1"
VOLTAGE"25V"
VALUE"0.1UF"
TOLERANCE"10%"
MATERIAL"X7R"
PACK_TYPE"0402"
CDS_LIB"pure_quanta"
PART_NUMBER"CH4104K1B00";
"B"
$PN"2"8;
"A"
$PN"1"62;
%"UNIVERSAL_GND"
"1","(2875,7575)","0","pure_quanta_power","I112";
;
CDS_LIB"pure_quanta_power"
HDL_POWER"GND";
"A"8;
%"UNIVERSAL_GND"
"1","(-1600,7450)","0","pure_quanta_power","I113";
;
CDS_LIB"pure_quanta_power"
HDL_POWER"GND";
"A"9;
%"Q_CAP"
"1","(-1600,7650)","0","pure_quanta","I114";
;
LOCATION"C1773"
$SEC"1"
CDS_SEC"1"
PACK_TYPE"0402"
MATERIAL"X7R"
TOLERANCE"10%"
VOLTAGE"25V"
VALUE"0.1UF"
CDS_LIB"pure_quanta"
PART_NUMBER"CH4104K1B00";
"B"
$PN"2"9;
"A"
$PN"1"64;
%"UNIVERSAL_GND"
"1","(-1650,6075)","0","pure_quanta_power","I115";
;
CDS_LIB"pure_quanta_power"
HDL_POWER"GND";
"A"10;
%"Q_CAP"
"1","(-1650,6275)","0","pure_quanta","I116";
;
LOCATION"C1772"
$SEC"1"
CDS_SEC"1"
VALUE"0.1UF"
VOLTAGE"25V"
MATERIAL"X7R"
PACK_TYPE"0402"
TOLERANCE"10%"
CDS_LIB"pure_quanta"
PART_NUMBER"CH4104K1B00";
"B"
$PN"2"10;
"A"
$PN"1"60;
%"MOSFET_NCH_DUAL"
"1","(-3525,6000)","0","pure_quanta","I117";
;
LOCATION"Q69"
$SEC"1"
CDS_SEC"1"
VALUE"PJT138K"
PART_TYPE"SMLF"
MATERIAL"IC"
CDS_LMAN_SYM_OUTLINE"-150,150,150,-150"
NEEDS_NO_SIZE"TRUE"
CDS_LIB"pure_quanta"
PART_NUMBER"BAM138K0003";
"D1"
$PN"6"72;
"G1"
$PN"2"70;
"S1"
$PN"1"6;
%"MOSFET_NCH_DUAL"
"1","(1050,7525)","0","pure_quanta","I118";
;
LOCATION"Q71"
$SEC"1"
CDS_SEC"1"
MATERIAL"IC"
PART_TYPE"SMLF"
VALUE"PJT138K"
CDS_LMAN_SYM_OUTLINE"-150,150,150,-150"
NEEDS_NO_SIZE"TRUE"
CDS_LIB"pure_quanta"
PART_NUMBER"BAM138K0003";
"D1"
$PN"6"73;
"G1"
$PN"2"58;
"S1"
$PN"1"36;
%"MOSFET_NCH_DUAL"
"2","(1975,6425)","0","pure_quanta","I119";
;
LOCATION"Q72"
SEC"2"
PART_TYPE"SMLF"
MATERIAL"IC"
VALUE"PJT138K"
CDS_LMAN_SYM_OUTLINE"-150,150,150,-150"
NEEDS_NO_SIZE"TRUE"
CDS_LIB"pure_quanta"
SEC_TYPE""
PART_NUMBER"BAM138K0003";
"S2"
$PN"4"5;
"G2"
$PN"5"74;
"D2"
$PN"3"66;
%"UNIVERSAL_GND"
"1","(-3450,4275)","0","pure_quanta_power","I12";
;
CDS_LIB"pure_quanta_power"
HDL_POWER"GND";
"A"11;
%"MOSFET_NCH_DUAL"
"2","(-2550,4925)","0","pure_quanta","I120";
;
LOCATION"Q70"
$SEC"2"
CDS_SEC"2"
PART_TYPE"SMLF"
VALUE"PJT138K"
MATERIAL"IC"
CDS_LMAN_SYM_OUTLINE"-150,150,150,-150"
NEEDS_NO_SIZE"TRUE"
CDS_LIB"pure_quanta"
PART_NUMBER"BAM138K0003";
"S2"
$PN"4"55;
"G2"
$PN"5"68;
"D2"
$PN"3"59;
%"MOSFET_NCH_DUAL"
"1","(1075,4775)","0","pure_quanta","I121";
;
LOCATION"Q74"
SEC"1"
VALUE"PJT138K"
MATERIAL"IC"
PART_TYPE"SMLF"
CDS_LMAN_SYM_OUTLINE"-150,150,150,-150"
NEEDS_NO_SIZE"TRUE"
CDS_LIB"pure_quanta"
SEC_TYPE""
PART_NUMBER"BAM138K0003";
"D1"
$PN"6"80;
"G1"
$PN"2"69;
"S1"
$PN"1"17;
%"MOSFET_NCH_DUAL"
"2","(2000,5050)","0","pure_quanta","I122";
;
LOCATION"Q74"
SEC"2"
MATERIAL"IC"
VALUE"PJT138K"
PART_TYPE"SMLF"
NEEDS_NO_SIZE"TRUE"
CDS_LMAN_SYM_OUTLINE"-150,150,150,-150"
CDS_LIB"pure_quanta"
SEC_TYPE""
PART_NUMBER"BAM138K0003";
"S2"
$PN"4"16;
"G2"
$PN"5"80;
"D2"
$PN"3"63;
%"UNIVERSAL_POWER"
"1","(2050,5800)","0","pure_quanta_power","I123";
;
HDL_POWER"P3V3_AUX"
CDS_LIB"pure_quanta_power";
"A"12;
%"Q_CAP"
"1","(2950,4875)","0","pure_quanta","I125";
;
LOCATION"C1804"
$SEC"1"
CDS_SEC"1"
VALUE"0.1UF"
TOLERANCE"10%"
MATERIAL"X7R"
PACK_TYPE"0402"
VOLTAGE"25V"
CDS_LIB"pure_quanta"
PART_NUMBER"CH4104K1B00";
"B"
$PN"2"13;
"A"
$PN"1"63;
%"UNIVERSAL_GND"
"1","(2950,4675)","0","pure_quanta_power","I126";
;
CDS_LIB"pure_quanta_power"
HDL_POWER"GND";
"A"13;
%"UNIVERSAL_POWER"
"1","(1125,5550)","0","pure_quanta_power","I128";
;
HDL_POWER"P3V3_AUX"
CDS_LIB"pure_quanta_power";
"A"14;
%"Q_RES"
"2","(1125,5250)","0","pure_quanta","I129";
;
LOCATION"R3034"
$SEC"1"
CDS_SEC"1"
VALUE"4.7K"
PACK_TYPE"0402LF"
MATERIAL"CHIP"
WATTAGE"1/16W"
TOLERANCE"5%"
CDS_LIB"pure_quanta"
PART_NUMBER"CS24702JB10";
"A"
$PN"1"14;
"B"
$PN"2"80;
%"UNIVERSAL_POWER"
"1","(-3525,8225)","0","pure_quanta_power","I13";
;
HDL_POWER"P3V3_AUX"
CDS_LIB"pure_quanta_power";
"A"15;
%"UNIVERSAL_GND"
"1","(2050,4675)","0","pure_quanta_power","I130";
;
CDS_LIB"pure_quanta_power"
HDL_POWER"GND";
"A"16;
%"UNIVERSAL_GND"
"1","(1125,4400)","0","pure_quanta_power","I131";
;
CDS_LIB"pure_quanta_power"
HDL_POWER"GND";
"A"17;
%"UNIVERSAL_POWER"
"1","(-125,5250)","0","pure_quanta_power","I132";
;
HDL_POWER"P3V3_AUX"
CDS_LIB"pure_quanta_power";
"A"18;
%"Q_RES"
"2","(-100,4525)","0","pure_quanta","I134";
;
LOCATION"R3032"
$SEC"1"
CDS_SEC"1"
VALUE"100K"
TOLERANCE"1%"
WATTAGE"1/16W"
MATERIAL"EMPTY"
PACK_TYPE"0402LF"
CDS_LIB"pure_quanta"
PART_NUMBER"CS41002FB09";
"A"
$PN"1"69;
"B"
$PN"2"19;
%"UNIVERSAL_GND"
"1","(-100,4325)","0","pure_quanta_power","I135";
;
CDS_LIB"pure_quanta_power"
HDL_POWER"GND";
"A"19;
%"UNIVERSAL_GND"
"1","(-4650,2625)","0","pure_quanta_power","I138";
;
CDS_LIB"pure_quanta_power"
HDL_POWER"GND";
"A"20;
%"Q_RES"
"2","(-4650,2825)","0","pure_quanta","I139";
;
LOCATION"R3028"
$SEC"1"
CDS_SEC"1"
PACK_TYPE"0402LF"
TOLERANCE"1%"
MATERIAL"EMPTY"
VALUE"100K"
WATTAGE"1/16W"
CDS_LIB"pure_quanta"
PART_NUMBER"CS41002FB09";
"A"
$PN"1"76;
"B"
$PN"2"20;
%"Q_RES"
"2","(-3525,8000)","0","pure_quanta","I14";
;
LOCATION"R2835"
$SEC"1"
CDS_SEC"1"
PACK_TYPE"0402LF"
VALUE"4.7K"
TOLERANCE"5%"
MATERIAL"CHIP"
WATTAGE"1/16W"
CDS_LIB"pure_quanta"
PART_NUMBER"CS24702JB10";
"A"
$PN"1"15;
"B"
$PN"2"79;
%"UNIVERSAL_POWER"
"1","(-4675,3550)","0","pure_quanta_power","I141";
;
HDL_POWER"P3V3_AUX"
CDS_LIB"pure_quanta_power";
"A"21;
%"UNIVERSAL_GND"
"1","(-3425,2700)","0","pure_quanta_power","I142";
;
CDS_LIB"pure_quanta_power"
HDL_POWER"GND";
"A"22;
%"UNIVERSAL_GND"
"1","(-2500,2975)","0","pure_quanta_power","I143";
;
CDS_LIB"pure_quanta_power"
HDL_POWER"GND";
"A"23;
%"Q_RES"
"2","(-3425,3550)","0","pure_quanta","I144";
;
LOCATION"R3029"
$SEC"1"
CDS_SEC"1"
TOLERANCE"5%"
MATERIAL"CHIP"
WATTAGE"1/16W"
PACK_TYPE"0402LF"
VALUE"4.7K"
CDS_LIB"pure_quanta"
PART_NUMBER"CS24702JB10";
"A"
$PN"1"24;
"B"
$PN"2"75;
%"UNIVERSAL_POWER"
"1","(-3425,3850)","0","pure_quanta_power","I145";
;
HDL_POWER"P3V3_AUX"
CDS_LIB"pure_quanta_power";
"A"24;
%"UNIVERSAL_GND"
"1","(-1600,2975)","0","pure_quanta_power","I147";
;
CDS_LIB"pure_quanta_power"
HDL_POWER"GND";
"A"25;
%"Q_CAP"
"1","(-1600,3175)","0","pure_quanta","I148";
;
LOCATION"C1802"
$SEC"1"
CDS_SEC"1"
VOLTAGE"25V"
VALUE"0.1UF"
MATERIAL"X7R"
PACK_TYPE"0402"
TOLERANCE"10%"
CDS_LIB"pure_quanta"
PART_NUMBER"CH4104K1B00";
"B"
$PN"2"25;
"A"
$PN"1"65;
%"UNIVERSAL_POWER"
"1","(-2500,4100)","0","pure_quanta_power","I150";
;
HDL_POWER"P3V3_AUX"
CDS_LIB"pure_quanta_power";
"A"26;
%"MOSFET_NCH_DUAL"
"2","(-2550,3350)","0","pure_quanta","I151";
;
LOCATION"Q75"
$SEC"2"
CDS_SEC"2"
PART_TYPE"SMLF"
VALUE"PJT138K"
MATERIAL"IC"
CDS_LIB"pure_quanta"
NEEDS_NO_SIZE"TRUE"
CDS_LMAN_SYM_OUTLINE"-150,150,150,-150"
PART_NUMBER"BAM138K0003";
"S2"
$PN"4"23;
"G2"
$PN"5"75;
"D2"
$PN"3"65;
%"MOSFET_NCH_DUAL"
"1","(-3475,3075)","0","pure_quanta","I152";
;
LOCATION"Q75"
$SEC"1"
CDS_SEC"1"
PART_TYPE"SMLF"
VALUE"PJT138K"
MATERIAL"IC"
CDS_LIB"pure_quanta"
NEEDS_NO_SIZE"TRUE"
CDS_LMAN_SYM_OUTLINE"-150,150,150,-150"
PART_NUMBER"BAM138K0003";
"D1"
$PN"6"75;
"G1"
$PN"2"76;
"S1"
$PN"1"22;
%"UNIVERSAL_POWER"
"1","(2000,4250)","0","pure_quanta_power","I153";
;
HDL_POWER"P3V3_AUX"
CDS_LIB"pure_quanta_power";
"A"27;
%"MOSFET_NCH_DUAL"
"1","(1025,3225)","0","pure_quanta","I154";
;
LOCATION"Q96"
$SEC"1"
CDS_SEC"1"
PART_TYPE"SMLF"
MATERIAL"IC"
VALUE"PJT138K"
CDS_LIB"pure_quanta"
NEEDS_NO_SIZE"TRUE"
CDS_LMAN_SYM_OUTLINE"-150,150,150,-150"
PART_NUMBER"BAM138K0003";
"D1"
$PN"6"77;
"G1"
$PN"2"78;
"S1"
$PN"1"32;
%"Q_CAP"
"1","(2900,3325)","0","pure_quanta","I156";
;
LOCATION"C1881"
$SEC"1"
CDS_SEC"1"
VALUE"0.1UF"
PACK_TYPE"0402"
VOLTAGE"25V"
MATERIAL"X7R"
TOLERANCE"10%"
CDS_LIB"pure_quanta"
PART_NUMBER"CH4104K1B00";
"B"
$PN"2"28;
"A"
$PN"1"61;
%"UNIVERSAL_GND"
"1","(2900,3125)","0","pure_quanta_power","I157";
;
CDS_LIB"pure_quanta_power"
HDL_POWER"GND";
"A"28;
%"Q_RES"
"2","(2000,3950)","0","pure_quanta","I158";
;
LOCATION"R3321"
$SEC"1"
CDS_SEC"1"
MATERIAL"CHIP"
WATTAGE"1/16W"
VALUE"100K"
TOLERANCE"1%"
PACK_TYPE"0402LF"
CDS_LIB"pure_quanta"
PART_NUMBER"CS41002FB09";
"A"
$PN"1"27;
"B"
$PN"2"61;
%"MOSFET_NCH_DUAL"
"2","(1950,3500)","0","pure_quanta","I159";
;
LOCATION"Q96"
$SEC"2"
CDS_SEC"2"
MATERIAL"IC"
VALUE"PJT138K"
PART_TYPE"SMLF"
CDS_LMAN_SYM_OUTLINE"-150,150,150,-150"
NEEDS_NO_SIZE"TRUE"
CDS_LIB"pure_quanta"
PART_NUMBER"BAM138K0003";
"S2"
$PN"4"30;
"G2"
$PN"5"77;
"D2"
$PN"3"61;
%"UNIVERSAL_POWER"
"1","(-3475,6750)","0","pure_quanta_power","I16";
;
HDL_POWER"P3V3_AUX"
CDS_LIB"pure_quanta_power";
"A"29;
%"UNIVERSAL_GND"
"1","(2000,3125)","0","pure_quanta_power","I160";
;
CDS_LIB"pure_quanta_power"
HDL_POWER"GND";
"A"30;
%"UNIVERSAL_POWER"
"1","(1075,4000)","0","pure_quanta_power","I161";
;
HDL_POWER"P3V3_AUX"
CDS_LIB"pure_quanta_power";
"A"31;
%"Q_RES"
"2","(1075,3700)","0","pure_quanta","I162";
;
LOCATION"R3320"
$SEC"1"
CDS_SEC"1"
MATERIAL"CHIP"
VALUE"4.7K"
PACK_TYPE"0402LF"
TOLERANCE"5%"
WATTAGE"1/16W"
CDS_LIB"pure_quanta"
PART_NUMBER"CS24702JB10";
"A"
$PN"1"31;
"B"
$PN"2"77;
%"UNIVERSAL_GND"
"1","(1075,2850)","0","pure_quanta_power","I163";
;
CDS_LIB"pure_quanta_power"
HDL_POWER"GND";
"A"32;
%"UNIVERSAL_POWER"
"1","(-175,3700)","0","pure_quanta_power","I164";
;
HDL_POWER"P3V3_AUX"
CDS_LIB"pure_quanta_power";
"A"33;
%"UNIVERSAL_GND"
"1","(-150,2775)","0","pure_quanta_power","I167";
;
CDS_LIB"pure_quanta_power"
HDL_POWER"GND";
"A"34;
%"Q_RES"
"2","(-175,3400)","0","pure_quanta","I171";
;
LOCATION"R3318"
$SEC"1"
CDS_SEC"1"
VALUE"100K"
MATERIAL"EMPTY"
TOLERANCE"1%"
WATTAGE"1/16W"
PACK_TYPE"0402LF"
CDS_LIB"pure_quanta"
PART_NUMBER"CS41002FB09";
"A"
$PN"1"33;
"B"
$PN"2"78;
%"Q_RES"
"2","(-150,2975)","0","pure_quanta","I172";
;
LOCATION"R3511"
$SEC"1"
CDS_SEC"1"
VALUE"54.9K"
MATERIAL"CHIP"
WATTAGE"1/16W"
TOLERANCE"1%"
PACK_TYPE"0402LF"
CDS_LIB"pure_quanta"
PART_NUMBER"CS35492FB03";
"A"
$PN"1"78;
"B"
$PN"2"34;
%"Q_RES"
"2","(-125,5900)","0","pure_quanta","I173";
;
LOCATION"R3513"
$SEC"1"
CDS_SEC"1"
PACK_TYPE"0402LF"
TOLERANCE"1%"
VALUE"54.9K"
MATERIAL"CHIP"
WATTAGE"1/16W"
CDS_LIB"pure_quanta"
PART_NUMBER"CS35492FB03";
"A"
$PN"1"57;
"B"
$PN"2"49;
%"Q_RES"
"2","(-150,6325)","0","pure_quanta","I174";
;
LOCATION"R3512"
$SEC"1"
CDS_SEC"1"
MATERIAL"EMPTY"
VALUE"100K"
TOLERANCE"1%"
WATTAGE"1/16W"
PACK_TYPE"0402LF"
CDS_LIB"pure_quanta"
PART_NUMBER"CS41002FB09";
"A"
$PN"1"44;
"B"
$PN"2"57;
%"Q_RES"
"2","(-125,4950)","0","pure_quanta","I175";
;
LOCATION"R3514"
$SEC"1"
CDS_SEC"1"
PACK_TYPE"0402LF"
VALUE"54.9K"
TOLERANCE"1%"
MATERIAL"CHIP"
WATTAGE"1/16W"
CDS_LIB"pure_quanta"
PART_NUMBER"CS35492FB03";
"A"
$PN"1"18;
"B"
$PN"2"69;
%"Q_RES"
"2","(-4675,3250)","0","pure_quanta","I176";
;
LOCATION"R3510"
$SEC"1"
CDS_SEC"1"
TOLERANCE"1%"
VALUE"54.9K"
WATTAGE"1/16W"
MATERIAL"CHIP"
PACK_TYPE"0402LF"
CDS_LIB"pure_quanta"
PART_NUMBER"CS35492FB03";
"A"
$PN"1"21;
"B"
$PN"2"76;
%"Q_RES"
"2","(-2375,8125)","2","pure_quanta","I177";
;
LOCATION"R2920"
$SEC"1"
CDS_SEC"1"
TOLERANCE"1%"
MATERIAL"CHIP"
WATTAGE"1/16W"
PACK_TYPE"0402LF"
VALUE"100K"
CDS_LIB"pure_quanta"
PART_NUMBER"CS41002FB09";
"A"
$PN"1"51;
"B"
$PN"2"64;
%"Q_RES"
"2","(-2500,3800)","2","pure_quanta","I178";
;
LOCATION"R3030"
$SEC"1"
CDS_SEC"1"
VALUE"100K"
TOLERANCE"1%"
WATTAGE"1/16W"
MATERIAL"CHIP"
PACK_TYPE"0402LF"
CDS_LIB"pure_quanta"
PART_NUMBER"CS41002FB09";
"A"
$PN"1"26;
"B"
$PN"2"65;
%"Q_RES"
"2","(2050,5500)","2","pure_quanta","I179";
;
LOCATION"R3035"
SEC"1"
VALUE"100K"
WATTAGE"1/16W"
MATERIAL"CHIP"
TOLERANCE"1%"
PACK_TYPE"0402LF"
SEC_TYPE"0402LF"
CDS_LIB"pure_quanta"
PART_NUMBER"CS41002FB09";
"A"
$PN"1"12;
"B"
$PN"2"63;
%"Q_RES"
"2","(-3475,6450)","0","pure_quanta","I18";
;
LOCATION"R2834"
$SEC"1"
CDS_SEC"1"
WATTAGE"1/16W"
TOLERANCE"5%"
PACK_TYPE"0402LF"
MATERIAL"CHIP"
VALUE"4.7K"
CDS_LIB"pure_quanta"
PART_NUMBER"CS24702JB10";
"A"
$PN"1"29;
"B"
$PN"2"72;
%"Q_RES"
"2","(-2500,5350)","2","pure_quanta","I180";
;
LOCATION"R2933"
$SEC"1"
CDS_SEC"1"
TOLERANCE"1%"
WATTAGE"1/16W"
PACK_TYPE"0402LF"
VALUE"100K"
MATERIAL"CHIP"
CDS_LIB"pure_quanta"
PART_NUMBER"CS41002FB09";
"A"
$PN"1"56;
"B"
$PN"2"59;
%"Q_RES"
"2","(-3450,5100)","0","pure_quanta","I19";
;
LOCATION"R2836"
$SEC"1"
CDS_SEC"1"
TOLERANCE"5%"
WATTAGE"1/16W"
MATERIAL"CHIP"
PACK_TYPE"0402LF"
VALUE"4.7K"
CDS_LIB"pure_quanta"
PART_NUMBER"CS24702JB10";
"A"
$PN"1"35;
"B"
$PN"2"68;
%"UNIVERSAL_POWER"
"1","(-3450,5400)","0","pure_quanta_power","I21";
;
HDL_POWER"P3V3_AUX"
CDS_LIB"pure_quanta_power";
"A"35;
%"UNIVERSAL_GND"
"1","(1100,7150)","0","pure_quanta_power","I23";
;
CDS_LIB"pure_quanta_power"
HDL_POWER"GND";
"A"36;
%"Q_RES"
"2","(1100,7925)","0","pure_quanta","I24";
;
LOCATION"R2841"
$SEC"1"
CDS_SEC"1"
VALUE"4.7K"
TOLERANCE"5%"
MATERIAL"CHIP"
WATTAGE"1/16W"
PACK_TYPE"0402LF"
CDS_LIB"pure_quanta"
PART_NUMBER"CS24702JB10";
"A"
$PN"1"37;
"B"
$PN"2"73;
%"UNIVERSAL_POWER"
"1","(1100,8225)","0","pure_quanta_power","I25";
;
HDL_POWER"P3V3_AUX"
CDS_LIB"pure_quanta_power";
"A"37;
%"UNIVERSAL_GND"
"1","(1100,5775)","0","pure_quanta_power","I29";
;
CDS_LIB"pure_quanta_power"
HDL_POWER"GND";
"A"38;
%"Q_RES"
"2","(1100,6625)","0","pure_quanta","I30";
;
LOCATION"R2842"
$SEC"1"
CDS_SEC"1"
VALUE"4.7K"
TOLERANCE"5%"
PACK_TYPE"0402LF"
MATERIAL"CHIP"
WATTAGE"1/16W"
CDS_LIB"pure_quanta"
PART_NUMBER"CS24702JB10";
"A"
$PN"1"39;
"B"
$PN"2"74;
%"UNIVERSAL_POWER"
"1","(1100,6925)","0","pure_quanta_power","I31";
;
HDL_POWER"P3V3_AUX"
CDS_LIB"pure_quanta_power";
"A"39;
%"MOSFET_NCH_DUAL"
"1","(-3575,7400)","0","pure_quanta","I33";
;
LOCATION"Q67"
$SEC"1"
CDS_SEC"1"
PART_TYPE"SMLF"
MATERIAL"IC"
VALUE"PJT138K"
CDS_LIB"pure_quanta"
NEEDS_NO_SIZE"TRUE"
CDS_LMAN_SYM_OUTLINE"-150,150,150,-150"
PART_NUMBER"BAM138K0003";
"D1"
$PN"6"79;
"G1"
$PN"2"71;
"S1"
$PN"1"1;
%"MOSFET_NCH_DUAL"
"1","(-3500,4650)","0","pure_quanta","I35";
;
LOCATION"Q70"
$SEC"1"
CDS_SEC"1"
MATERIAL"IC"
VALUE"PJT138K"
PART_TYPE"SMLF"
CDS_LMAN_SYM_OUTLINE"-150,150,150,-150"
NEEDS_NO_SIZE"TRUE"
CDS_LIB"pure_quanta"
PART_NUMBER"BAM138K0003";
"D1"
$PN"6"68;
"G1"
$PN"2"67;
"S1"
$PN"1"11;
%"MOSFET_NCH_DUAL"
"1","(1050,6150)","0","pure_quanta","I37";
;
LOCATION"Q72"
$SEC"1"
CDS_SEC"1"
PART_TYPE"SMLF"
VALUE"PJT138K"
MATERIAL"IC"
CDS_LMAN_SYM_OUTLINE"-150,150,150,-150"
NEEDS_NO_SIZE"TRUE"
CDS_LIB"pure_quanta"
PART_NUMBER"BAM138K0003";
"D1"
$PN"6"74;
"G1"
$PN"2"57;
"S1"
$PN"1"38;
%"UNIVERSAL_POWER"
"1","(-4700,7875)","0","pure_quanta_power","I46";
;
HDL_POWER"P3V3_AUX"
CDS_LIB"pure_quanta_power";
"A"40;
%"UNIVERSAL_POWER"
"1","(-4675,6475)","0","pure_quanta_power","I47";
;
HDL_POWER"P3V3_AUX"
CDS_LIB"pure_quanta_power";
"A"41;
%"UNIVERSAL_POWER"
"1","(-4625,5125)","0","pure_quanta_power","I49";
;
HDL_POWER"P3V3_AUX"
CDS_LIB"pure_quanta_power";
"A"42;
%"UNIVERSAL_POWER"
"1","(-150,8000)","0","pure_quanta_power","I51";
;
HDL_POWER"P3V3_AUX"
CDS_LIB"pure_quanta_power";
"A"43;
%"UNIVERSAL_POWER"
"1","(-150,6625)","0","pure_quanta_power","I53";
;
HDL_POWER"P3V3_AUX"
CDS_LIB"pure_quanta_power";
"A"44;
%"UNIVERSAL_GND"
"1","(-4675,6950)","0","pure_quanta_power","I55";
;
CDS_LIB"pure_quanta_power"
HDL_POWER"GND";
"A"45;
%"Q_RES"
"2","(-4675,7150)","0","pure_quanta","I56";
;
LOCATION"R2831"
$SEC"1"
CDS_SEC"1"
PACK_TYPE"0402LF"
WATTAGE"1/16W"
MATERIAL"EMPTY"
TOLERANCE"1%"
VALUE"100K"
CDS_LIB"pure_quanta"
PART_NUMBER"CS41002FB09";
"A"
$PN"1"71;
"B"
$PN"2"45;
%"UNIVERSAL_GND"
"1","(-4650,5575)","0","pure_quanta_power","I57";
;
CDS_LIB"pure_quanta_power"
HDL_POWER"GND";
"A"46;
%"Q_RES"
"2","(-4650,5750)","0","pure_quanta","I58";
;
LOCATION"R2829"
$SEC"1"
CDS_SEC"1"
VALUE"100K"
TOLERANCE"1%"
PACK_TYPE"0402LF"
MATERIAL"EMPTY"
WATTAGE"1/16W"
CDS_LIB"pure_quanta"
PART_NUMBER"CS41002FB09";
"A"
$PN"1"70;
"B"
$PN"2"46;
%"UNIVERSAL_GND"
"1","(-4600,4225)","0","pure_quanta_power","I59";
;
CDS_LIB"pure_quanta_power"
HDL_POWER"GND";
"A"47;
%"Q_RES"
"2","(-4600,4400)","0","pure_quanta","I60";
;
LOCATION"R2833"
$SEC"1"
CDS_SEC"1"
VALUE"100K"
TOLERANCE"1%"
WATTAGE"1/16W"
MATERIAL"EMPTY"
PACK_TYPE"0402LF"
CDS_LIB"pure_quanta"
PART_NUMBER"CS41002FB09";
"A"
$PN"1"67;
"B"
$PN"2"47;
%"UNIVERSAL_GND"
"1","(-125,7100)","0","pure_quanta_power","I61";
;
CDS_LIB"pure_quanta_power"
HDL_POWER"GND";
"A"48;
%"Q_RES"
"2","(-125,7275)","0","pure_quanta","I62";
;
LOCATION"R2838"
$SEC"1"
CDS_SEC"1"
VALUE"100K"
TOLERANCE"1%"
WATTAGE"1/16W"
MATERIAL"CHIP"
PACK_TYPE"0402LF"
CDS_LIB"pure_quanta"
PART_NUMBER"CS41002FB09";
"A"
$PN"1"58;
"B"
$PN"2"48;
%"UNIVERSAL_GND"
"1","(-125,5700)","0","pure_quanta_power","I63";
;
CDS_LIB"pure_quanta_power"
HDL_POWER"GND";
"A"49;
%"Q_RES"
"2","(-4675,6225)","0","pure_quanta","I66";
;
LOCATION"R2828"
$SEC"1"
CDS_SEC"1"
VALUE"100K"
MATERIAL"CHIP"
TOLERANCE"1%"
WATTAGE"1/16W"
PACK_TYPE"0402LF"
CDS_LIB"pure_quanta"
PART_NUMBER"CS41002FB09";
"A"
$PN"1"41;
"B"
$PN"2"70;
%"Q_RES"
"2","(-4625,4875)","0","pure_quanta","I67";
;
LOCATION"R2832"
$SEC"1"
CDS_SEC"1"
WATTAGE"1/16W"
TOLERANCE"1%"
VALUE"100K"
PACK_TYPE"0402LF"
MATERIAL"CHIP"
CDS_LIB"pure_quanta"
PART_NUMBER"CS41002FB09";
"A"
$PN"1"42;
"B"
$PN"2"67;
%"Q_RES"
"2","(-4700,7625)","0","pure_quanta","I68";
;
LOCATION"R2830"
$SEC"1"
CDS_SEC"1"
VALUE"100K"
TOLERANCE"1%"
WATTAGE"1/16W"
MATERIAL"CHIP"
PACK_TYPE"0402LF"
CDS_LIB"pure_quanta"
PART_NUMBER"CS41002FB09";
"A"
$PN"1"40;
"B"
$PN"2"71;
%"Q_RES"
"2","(-150,7700)","0","pure_quanta","I80";
;
LOCATION"R2837"
$SEC"1"
CDS_SEC"1"
TOLERANCE"1%"
WATTAGE"1/16W"
MATERIAL"EMPTY"
PACK_TYPE"0402LF"
VALUE"100K"
CDS_LIB"pure_quanta"
PART_NUMBER"CS41002FB09";
"A"
$PN"1"43;
"B"
$PN"2"58;
%"MOSFET_NCH_DUAL"
"2","(-2425,7700)","0","pure_quanta","I82";
;
LOCATION"Q67"
$SEC"2"
CDS_SEC"2"
MATERIAL"IC"
PART_TYPE"SMLF"
VALUE"PJT138K"
CDS_LMAN_SYM_OUTLINE"-150,150,150,-150"
NEEDS_NO_SIZE"TRUE"
CDS_LIB"pure_quanta"
PART_NUMBER"BAM138K0003";
"S2"
$PN"4"50;
"G2"
$PN"5"79;
"D2"
$PN"3"64;
%"UNIVERSAL_GND"
"1","(-2375,7325)","0","pure_quanta_power","I83";
;
CDS_LIB"pure_quanta_power"
HDL_POWER"GND";
"A"50;
%"UNIVERSAL_POWER"
"1","(-2375,8350)","0","pure_quanta_power","I85";
;
HDL_POWER"P3V3_AUX"
CDS_LIB"pure_quanta_power";
"A"51;
%"MOSFET_NCH_DUAL"
"2","(-2525,6300)","0","pure_quanta","I88";
;
LOCATION"Q69"
$SEC"2"
CDS_SEC"2"
PART_TYPE"SMLF"
VALUE"PJT138K"
MATERIAL"IC"
CDS_LMAN_SYM_OUTLINE"-150,150,150,-150"
NEEDS_NO_SIZE"TRUE"
CDS_LIB"pure_quanta"
PART_NUMBER"BAM138K0003";
"S2"
$PN"4"52;
"G2"
$PN"5"72;
"D2"
$PN"3"60;
%"UNIVERSAL_GND"
"1","(-2475,5925)","0","pure_quanta_power","I89";
;
CDS_LIB"pure_quanta_power"
HDL_POWER"GND";
"A"52;
%"UNIVERSAL_POWER"
"1","(-2475,6950)","0","pure_quanta_power","I90";
;
HDL_POWER"P3V3_AUX"
CDS_LIB"pure_quanta_power";
"A"53;
%"Q_RES"
"2","(-2475,6725)","0","pure_quanta","I91";
;
LOCATION"R2919"
$SEC"1"
CDS_SEC"1"
PACK_TYPE"0402LF"
MATERIAL"CHIP"
WATTAGE"1/16W"
VALUE"100K"
TOLERANCE"1%"
CDS_LIB"pure_quanta"
PART_NUMBER"CS41002FB09";
"A"
$PN"1"53;
"B"
$PN"2"60;
%"Q_CAP"
"1","(-1600,4925)","0","pure_quanta","I92";
;
LOCATION"C1754"
$SEC"1"
CDS_SEC"1"
VALUE"0.1UF"
TOLERANCE"10%"
MATERIAL"X7R"
PACK_TYPE"0402"
VOLTAGE"25V"
CDS_LIB"pure_quanta"
PART_NUMBER"CH4104K1B00";
"B"
$PN"2"54;
"A"
$PN"1"59;
%"UNIVERSAL_GND"
"1","(-1600,4725)","0","pure_quanta_power","I93";
;
CDS_LIB"pure_quanta_power"
HDL_POWER"GND";
"A"54;
%"UNIVERSAL_GND"
"1","(-2500,4550)","0","pure_quanta_power","I96";
;
CDS_LIB"pure_quanta_power"
HDL_POWER"GND";
"A"55;
%"UNIVERSAL_POWER"
"1","(-2500,5650)","0","pure_quanta_power","I98";
;
HDL_POWER"P3V3_AUX"
CDS_LIB"pure_quanta_power";
"A"56;
END.
